(kicad_pcb
	(version 20241229)
	(generator "pcbnew")
	(generator_version "9.0")
	(general
		(thickness 1.599998)
		(legacy_teardrops no)
	)
	(paper "A4")
	(title_block
		(title "Artix - Datacenter Secure Control Module (DC-SCM)")
		(date "2024-11-06")
		(rev "1.1.3")
		(comment 9 "footprints 406-411 of 544")
	)
	(layers
		(0 "F.Cu" signal)
		(4 "In1.Cu" signal)
		(6 "In2.Cu" signal)
		(8 "In3.Cu" signal)
		(10 "In4.Cu" signal)
		(12 "In5.Cu" signal)
		(14 "In6.Cu" signal)
		(2 "B.Cu" signal)
		(9 "F.Adhes" user "F.Adhesive")
		(11 "B.Adhes" user "B.Adhesive")
		(13 "F.Paste" user)
		(15 "B.Paste" user)
		(5 "F.SilkS" user "F.Silkscreen")
		(7 "B.SilkS" user "B.Silkscreen")
		(1 "F.Mask" user)
		(3 "B.Mask" user)
		(17 "Dwgs.User" user "User.Drawings")
		(19 "Cmts.User" user "User.Comments")
		(21 "Eco1.User" user "User.Eco1")
		(23 "Eco2.User" user "User.Eco2")
		(25 "Edge.Cuts" user)
		(27 "Margin" user)
		(31 "F.CrtYd" user "F.Courtyard")
		(29 "B.CrtYd" user "B.Courtyard")
		(35 "F.Fab" user)
		(33 "B.Fab" user)
	)
	(footprint "antmicro-footprints:R_0402_1005Metric"
		(layer "B.Cu")
		(at 71.19 118.125)
		(descr "Resistor SMD 0402")
		(tags "resistor SMD 0402")
		(property "Reference" "R37"
			(at -2.99 0.375 0)
			(layer "B.SilkS")
			(effects
				(font
					(size 0.7 0.7)
					(thickness 0.15)
				)
				(justify right bottom mirror)
			)
		)
		(property "Value" "R_10k_0402"
			(at 0 -1.4 0)
			(layer "B.Fab")
			(effects
				(font
					(size 0.7 0.7)
					(thickness 0.15)
				)
				(justify right bottom mirror)
			)
		)
		(property "Datasheet" "https://www.bourns.com/docs/product-datasheets/cr.pdf"
			(at 0 0 0)
			(layer "F.Fab")
			(hide yes)
			(effects
				(font
					(size 1.27 1.27)
					(thickness 0.15)
				)
			)
		)
		(property "Description" "SMD Chip Resistor, 10 kohm, ± 1%, 62.5 mW, 0402 [1005 Metric], Thick Film, General Purpose"
			(at 0 0 0)
			(layer "F.Fab")
			(hide yes)
			(effects
				(font
					(size 1.27 1.27)
					(thickness 0.15)
				)
			)
		)
		(property "Author" "Antmicro"
			(at 0 0 0)
			(layer "B.Fab")
			(hide yes)
			(effects
				(font
					(size 1 1)
					(thickness 0.15)
				)
				(justify mirror)
			)
		)
		(property "License" "Apache-2.0"
			(at 0 0 0)
			(layer "B.Fab")
			(hide yes)
			(effects
				(font
					(size 1 1)
					(thickness 0.15)
				)
				(justify mirror)
			)
		)
		(property "MPN" "CR0402-FX-1002GLF"
			(at 0 0 0)
			(layer "B.Fab")
			(hide yes)
			(effects
				(font
					(size 1 1)
					(thickness 0.15)
				)
				(justify mirror)
			)
		)
		(property "Manufacturer" "Bourns"
			(at 0 0 0)
			(layer "B.Fab")
			(hide yes)
			(effects
				(font
					(size 1 1)
					(thickness 0.15)
				)
				(justify mirror)
			)
		)
		(property "Tolerance" "1%"
			(at 0 0 0)
			(layer "B.Fab")
			(hide yes)
			(effects
				(font
					(size 1 1)
					(thickness 0.15)
				)
				(justify mirror)
			)
		)
		(property "Val" "10k"
			(at 0 0 0)
			(layer "B.Fab")
			(hide yes)
			(effects
				(font
					(size 1 1)
					(thickness 0.15)
				)
				(justify mirror)
			)
		)
		(sheetname "/RoT/")
		(sheetfile "rot.kicad_sch")
		(attr smd)
		(fp_rect
			(start -0.925 0.47)
			(end 0.925 -0.47)
			(stroke
				(width 0.05)
				(type default)
			)
			(fill no)
			(layer "B.CrtYd")
		)
		(fp_rect
			(start -0.5 0.25)
			(end 0.5 -0.25)
			(stroke
				(width 0.15)
				(type solid)
			)
			(fill no)
			(layer "B.Fab")
		)
		(pad "1" smd roundrect
			(at -0.48 0)
			(size 0.59 0.64)
			(layers "B.Cu" "B.Mask" "B.Paste")
			(roundrect_rratio 0.25)
			(net 128 "QSPIB2_D3")
			(pintype "passive")
		)
		(pad "2" smd roundrect
			(at 0.48 0)
			(size 0.59 0.64)
			(layers "B.Cu" "B.Mask" "B.Paste")
			(roundrect_rratio 0.25)
			(net 2 "VCC3V3")
			(pintype "passive")
		)
	)
	(footprint "antmicro-footprints:R_0402_1005Metric"
		(layer "B.Cu")
		(at 71.19 121.125)
		(descr "Resistor SMD 0402")
		(tags "resistor SMD 0402")
		(property "Reference" "R33"
			(at -2.99 0.375 0)
			(layer "B.SilkS")
			(effects
				(font
					(size 0.7 0.7)
					(thickness 0.15)
				)
				(justify right bottom mirror)
			)
		)
		(property "Value" "R_10k_0402"
			(at 0 -1.4 0)
			(layer "B.Fab")
			(effects
				(font
					(size 0.7 0.7)
					(thickness 0.15)
				)
				(justify right bottom mirror)
			)
		)
		(property "Datasheet" "https://www.bourns.com/docs/product-datasheets/cr.pdf"
			(at 0 0 0)
			(layer "F.Fab")
			(hide yes)
			(effects
				(font
					(size 1.27 1.27)
					(thickness 0.15)
				)
			)
		)
		(property "Description" "SMD Chip Resistor, 10 kohm, ± 1%, 62.5 mW, 0402 [1005 Metric], Thick Film, General Purpose"
			(at 0 0 0)
			(layer "F.Fab")
			(hide yes)
			(effects
				(font
					(size 1.27 1.27)
					(thickness 0.15)
				)
			)
		)
		(property "Author" "Antmicro"
			(at 0 0 0)
			(layer "B.Fab")
			(hide yes)
			(effects
				(font
					(size 1 1)
					(thickness 0.15)
				)
				(justify mirror)
			)
		)
		(property "License" "Apache-2.0"
			(at 0 0 0)
			(layer "B.Fab")
			(hide yes)
			(effects
				(font
					(size 1 1)
					(thickness 0.15)
				)
				(justify mirror)
			)
		)
		(property "MPN" "CR0402-FX-1002GLF"
			(at 0 0 0)
			(layer "B.Fab")
			(hide yes)
			(effects
				(font
					(size 1 1)
					(thickness 0.15)
				)
				(justify mirror)
			)
		)
		(property "Manufacturer" "Bourns"
			(at 0 0 0)
			(layer "B.Fab")
			(hide yes)
			(effects
				(font
					(size 1 1)
					(thickness 0.15)
				)
				(justify mirror)
			)
		)
		(property "Tolerance" "1%"
			(at 0 0 0)
			(layer "B.Fab")
			(hide yes)
			(effects
				(font
					(size 1 1)
					(thickness 0.15)
				)
				(justify mirror)
			)
		)
		(property "Val" "10k"
			(at 0 0 0)
			(layer "B.Fab")
			(hide yes)
			(effects
				(font
					(size 1 1)
					(thickness 0.15)
				)
				(justify mirror)
			)
		)
		(sheetname "/RoT/")
		(sheetfile "rot.kicad_sch")
		(attr smd)
		(fp_rect
			(start -0.925 0.47)
			(end 0.925 -0.47)
			(stroke
				(width 0.05)
				(type default)
			)
			(fill no)
			(layer "B.CrtYd")
		)
		(fp_rect
			(start -0.5 0.25)
			(end 0.5 -0.25)
			(stroke
				(width 0.15)
				(type solid)
			)
			(fill no)
			(layer "B.Fab")
		)
		(pad "1" smd roundrect
			(at -0.48 0)
			(size 0.59 0.64)
			(layers "B.Cu" "B.Mask" "B.Paste")
			(roundrect_rratio 0.25)
			(net 127 "QSPIB2_D2")
			(pintype "passive")
		)
		(pad "2" smd roundrect
			(at 0.48 0)
			(size 0.59 0.64)
			(layers "B.Cu" "B.Mask" "B.Paste")
			(roundrect_rratio 0.25)
			(net 2 "VCC3V3")
			(pintype "passive")
		)
	)
	(footprint "antmicro-footprints:C_0402_1005Metric"
		(layer "B.Cu")
		(at 64.605 117.59 90)
		(descr "Capacitor SMD 0402")
		(tags "capacitor SMD 0402")
		(property "Reference" "C35"
			(at -1.01 -0.605 90)
			(layer "B.SilkS")
			(effects
				(font
					(size 0.7 0.7)
					(thickness 0.15)
				)
				(justify right bottom mirror)
			)
		)
		(property "Value" "C_470n_0402"
			(at 0 -1.4 90)
			(layer "B.Fab")
			(effects
				(font
					(size 0.7 0.7)
					(thickness 0.15)
				)
				(justify right bottom mirror)
			)
		)
		(property "Datasheet" "https://product.tdk.com/en/search/capacitor/ceramic/mlcc/info?part_no=C1005X5R1E474M050BB"
			(at 0 0 90)
			(layer "F.Fab")
			(hide yes)
			(effects
				(font
					(size 1.27 1.27)
					(thickness 0.15)
				)
			)
		)
		(property "Description" "SMD Multilayer Ceramic Capacitor, 0.47 µF, 25 V, 0402 [1005 Metric], ± 20%, X5R, C"
			(at 0 0 90)
			(layer "F.Fab")
			(hide yes)
			(effects
				(font
					(size 1.27 1.27)
					(thickness 0.15)
				)
			)
		)
		(property "Author" "Antmicro"
			(at 182.195 52.985 0)
			(layer "B.Fab")
			(hide yes)
			(effects
				(font
					(size 1 1)
					(thickness 0.15)
				)
				(justify mirror)
			)
		)
		(property "Dielectric" ""
			(at 182.195 52.985 0)
			(layer "B.Fab")
			(hide yes)
			(effects
				(font
					(size 1 1)
					(thickness 0.15)
				)
				(justify mirror)
			)
		)
		(property "License" "Apache-2.0"
			(at 182.195 52.985 0)
			(layer "B.Fab")
			(hide yes)
			(effects
				(font
					(size 1 1)
					(thickness 0.15)
				)
				(justify mirror)
			)
		)
		(property "MPN" "C1005X5R1E474M050BB"
			(at 182.195 52.985 0)
			(layer "B.Fab")
			(hide yes)
			(effects
				(font
					(size 1 1)
					(thickness 0.15)
				)
				(justify mirror)
			)
		)
		(property "Manufacturer" "TDK"
			(at 182.195 52.985 0)
			(layer "B.Fab")
			(hide yes)
			(effects
				(font
					(size 1 1)
					(thickness 0.15)
				)
				(justify mirror)
			)
		)
		(property "Val" "470n"
			(at 182.195 52.985 0)
			(layer "B.Fab")
			(hide yes)
			(effects
				(font
					(size 1 1)
					(thickness 0.15)
				)
				(justify mirror)
			)
		)
		(property "Voltage" ""
			(at 182.195 52.985 0)
			(layer "B.Fab")
			(hide yes)
			(effects
				(font
					(size 1 1)
					(thickness 0.15)
				)
				(justify mirror)
			)
		)
		(sheetname "/RoT/")
		(sheetfile "rot.kicad_sch")
		(attr smd)
		(fp_rect
			(start -0.925 0.47)
			(end 0.925 -0.47)
			(stroke
				(width 0.05)
				(type default)
			)
			(fill no)
			(layer "B.CrtYd")
		)
		(fp_line
			(start 0.504 -0.248)
			(end -0.494 -0.248)
			(stroke
				(width 0.15)
				(type solid)
			)
			(layer "B.Fab")
		)
		(fp_line
			(start -0.494 -0.248)
			(end -0.494 0.25)
			(stroke
				(width 0.15)
				(type solid)
			)
			(layer "B.Fab")
		)
		(fp_line
			(start 0.504 0.25)
			(end 0.504 -0.248)
			(stroke
				(width 0.15)
				(type solid)
			)
			(layer "B.Fab")
		)
		(fp_line
			(start -0.494 0.25)
			(end 0.504 0.25)
			(stroke
				(width 0.15)
				(type solid)
			)
			(layer "B.Fab")
		)
		(pad "1" smd roundrect
			(at -0.48 0 90)
			(size 0.59 0.64)
			(layers "B.Cu" "B.Mask" "B.Paste")
			(roundrect_rratio 0.25)
			(net 1 "GND")
			(pintype "passive")
		)
		(pad "2" smd roundrect
			(at 0.48 0 90)
			(size 0.59 0.64)
			(layers "B.Cu" "B.Mask" "B.Paste")
			(roundrect_rratio 0.25)
			(net 2 "VCC3V3")
			(pintype "passive")
		)
	)
	(footprint "antmicro-footprints:R_0402_1005Metric"
		(layer "B.Cu")
		(at 71.24 144.925)
		(descr "Resistor SMD 0402")
		(tags "resistor SMD 0402")
		(property "Reference" "R32"
			(at -2.95 0.425 0)
			(layer "B.SilkS")
			(effects
				(font
					(size 0.7 0.7)
					(thickness 0.15)
				)
				(justify right bottom mirror)
			)
		)
		(property "Value" "R_10k_0402"
			(at 0 -1.4 0)
			(layer "B.Fab")
			(effects
				(font
					(size 0.7 0.7)
					(thickness 0.15)
				)
				(justify right bottom mirror)
			)
		)
		(property "Datasheet" "https://www.bourns.com/docs/product-datasheets/cr.pdf"
			(at 0 0 0)
			(layer "F.Fab")
			(hide yes)
			(effects
				(font
					(size 1.27 1.27)
					(thickness 0.15)
				)
			)
		)
		(property "Description" "SMD Chip Resistor, 10 kohm, ± 1%, 62.5 mW, 0402 [1005 Metric], Thick Film, General Purpose"
			(at 0 0 0)
			(layer "F.Fab")
			(hide yes)
			(effects
				(font
					(size 1.27 1.27)
					(thickness 0.15)
				)
			)
		)
		(property "Author" "Antmicro"
			(at 0 0 0)
			(layer "B.Fab")
			(hide yes)
			(effects
				(font
					(size 1 1)
					(thickness 0.15)
				)
				(justify mirror)
			)
		)
		(property "License" "Apache-2.0"
			(at 0 0 0)
			(layer "B.Fab")
			(hide yes)
			(effects
				(font
					(size 1 1)
					(thickness 0.15)
				)
				(justify mirror)
			)
		)
		(property "MPN" "CR0402-FX-1002GLF"
			(at 0 0 0)
			(layer "B.Fab")
			(hide yes)
			(effects
				(font
					(size 1 1)
					(thickness 0.15)
				)
				(justify mirror)
			)
		)
		(property "Manufacturer" "Bourns"
			(at 0 0 0)
			(layer "B.Fab")
			(hide yes)
			(effects
				(font
					(size 1 1)
					(thickness 0.15)
				)
				(justify mirror)
			)
		)
		(property "Tolerance" "1%"
			(at 0 0 0)
			(layer "B.Fab")
			(hide yes)
			(effects
				(font
					(size 1 1)
					(thickness 0.15)
				)
				(justify mirror)
			)
		)
		(property "Val" "10k"
			(at 0 0 0)
			(layer "B.Fab")
			(hide yes)
			(effects
				(font
					(size 1 1)
					(thickness 0.15)
				)
				(justify mirror)
			)
		)
		(sheetname "/RoT/")
		(sheetfile "rot.kicad_sch")
		(attr smd)
		(fp_rect
			(start -0.925 0.47)
			(end 0.925 -0.47)
			(stroke
				(width 0.05)
				(type default)
			)
			(fill no)
			(layer "B.CrtYd")
		)
		(fp_rect
			(start -0.5 0.25)
			(end 0.5 -0.25)
			(stroke
				(width 0.15)
				(type solid)
			)
			(fill no)
			(layer "B.Fab")
		)
		(pad "1" smd roundrect
			(at -0.48 0)
			(size 0.59 0.64)
			(layers "B.Cu" "B.Mask" "B.Paste")
			(roundrect_rratio 0.25)
			(net 131 "QSPIA1_D0")
			(pintype "passive")
		)
		(pad "2" smd roundrect
			(at 0.48 0)
			(size 0.59 0.64)
			(layers "B.Cu" "B.Mask" "B.Paste")
			(roundrect_rratio 0.25)
			(net 2 "VCC3V3")
			(pintype "passive")
		)
	)
	(footprint "antmicro-footprints:R_0402_1005Metric"
		(layer "B.Cu")
		(at 71.15 125.675)
		(descr "Resistor SMD 0402")
		(tags "resistor SMD 0402")
		(property "Reference" "R30"
			(at -2.95 0.425 0)
			(layer "B.SilkS")
			(effects
				(font
					(size 0.7 0.7)
					(thickness 0.15)
				)
				(justify right bottom mirror)
			)
		)
		(property "Value" "R_10k_0402"
			(at 0 -1.4 0)
			(layer "B.Fab")
			(effects
				(font
					(size 0.7 0.7)
					(thickness 0.15)
				)
				(justify right bottom mirror)
			)
		)
		(property "Datasheet" "https://www.bourns.com/docs/product-datasheets/cr.pdf"
			(at 0 0 0)
			(layer "F.Fab")
			(hide yes)
			(effects
				(font
					(size 1.27 1.27)
					(thickness 0.15)
				)
			)
		)
		(property "Description" "SMD Chip Resistor, 10 kohm, ± 1%, 62.5 mW, 0402 [1005 Metric], Thick Film, General Purpose"
			(at 0 0 0)
			(layer "F.Fab")
			(hide yes)
			(effects
				(font
					(size 1.27 1.27)
					(thickness 0.15)
				)
			)
		)
		(property "Author" "Antmicro"
			(at 0 0 0)
			(layer "B.Fab")
			(hide yes)
			(effects
				(font
					(size 1 1)
					(thickness 0.15)
				)
				(justify mirror)
			)
		)
		(property "License" "Apache-2.0"
			(at 0 0 0)
			(layer "B.Fab")
			(hide yes)
			(effects
				(font
					(size 1 1)
					(thickness 0.15)
				)
				(justify mirror)
			)
		)
		(property "MPN" "CR0402-FX-1002GLF"
			(at 0 0 0)
			(layer "B.Fab")
			(hide yes)
			(effects
				(font
					(size 1 1)
					(thickness 0.15)
				)
				(justify mirror)
			)
		)
		(property "Manufacturer" "Bourns"
			(at 0 0 0)
			(layer "B.Fab")
			(hide yes)
			(effects
				(font
					(size 1 1)
					(thickness 0.15)
				)
				(justify mirror)
			)
		)
		(property "Tolerance" "1%"
			(at 0 0 0)
			(layer "B.Fab")
			(hide yes)
			(effects
				(font
					(size 1 1)
					(thickness 0.15)
				)
				(justify mirror)
			)
		)
		(property "Val" "10k"
			(at 0 0 0)
			(layer "B.Fab")
			(hide yes)
			(effects
				(font
					(size 1 1)
					(thickness 0.15)
				)
				(justify mirror)
			)
		)
		(sheetname "/RoT/")
		(sheetfile "rot.kicad_sch")
		(attr smd)
		(fp_rect
			(start -0.925 0.47)
			(end 0.925 -0.47)
			(stroke
				(width 0.05)
				(type default)
			)
			(fill no)
			(layer "B.CrtYd")
		)
		(fp_rect
			(start -0.5 0.25)
			(end 0.5 -0.25)
			(stroke
				(width 0.15)
				(type solid)
			)
			(fill no)
			(layer "B.Fab")
		)
		(pad "1" smd roundrect
			(at -0.48 0)
			(size 0.59 0.64)
			(layers "B.Cu" "B.Mask" "B.Paste")
			(roundrect_rratio 0.25)
			(net 120 "QSPIB1_D0")
			(pintype "passive")
		)
		(pad "2" smd roundrect
			(at 0.48 0)
			(size 0.59 0.64)
			(layers "B.Cu" "B.Mask" "B.Paste")
			(roundrect_rratio 0.25)
			(net 2 "VCC3V3")
			(pintype "passive")
		)
	)
	(footprint "antmicro-footprints:R_0402_1005Metric"
		(layer "B.Cu")
		(at 71.24 145.925 180)
		(descr "Resistor SMD 0402")
		(tags "resistor SMD 0402")
		(property "Reference" "R28"
			(at 0.74 -0.375 0)
			(layer "B.SilkS")
			(effects
				(font
					(size 0.7 0.7)
					(thickness 0.15)
				)
				(justify left bottom mirror)
			)
		)
		(property "Value" "R_1k_0402"
			(at 0 -1.4 0)
			(layer "B.Fab")
			(effects
				(font
					(size 0.7 0.7)
					(thickness 0.15)
				)
				(justify left bottom mirror)
			)
		)
		(property "Datasheet" "https://www.bourns.com/docs/product-datasheets/cr.pdf"
			(at 0 0 180)
			(layer "F.Fab")
			(hide yes)
			(effects
				(font
					(size 1.27 1.27)
					(thickness 0.15)
				)
			)
		)
		(property "Description" "SMD Chip Resistor, 1 kohm, ± 1%, 63 mW, 0402 [1005 Metric], Thick Film, General Purpose"
			(at 0 0 180)
			(layer "F.Fab")
			(hide yes)
			(effects
				(font
					(size 1.27 1.27)
					(thickness 0.15)
				)
			)
		)
		(property "Author" "Antmicro"
			(at 142.48 291.85 0)
			(layer "B.Fab")
			(hide yes)
			(effects
				(font
					(size 1 1)
					(thickness 0.15)
				)
				(justify mirror)
			)
		)
		(property "License" "Apache-2.0"
			(at 142.48 291.85 0)
			(layer "B.Fab")
			(hide yes)
			(effects
				(font
					(size 1 1)
					(thickness 0.15)
				)
				(justify mirror)
			)
		)
		(property "MPN" "CR0402-FX-1001GLF"
			(at 142.48 291.85 0)
			(layer "B.Fab")
			(hide yes)
			(effects
				(font
					(size 1 1)
					(thickness 0.15)
				)
				(justify mirror)
			)
		)
		(property "Manufacturer" "Bourns"
			(at 142.48 291.85 0)
			(layer "B.Fab")
			(hide yes)
			(effects
				(font
					(size 1 1)
					(thickness 0.15)
				)
				(justify mirror)
			)
		)
		(property "Tolerance" "1%"
			(at 142.48 291.85 0)
			(layer "B.Fab")
			(hide yes)
			(effects
				(font
					(size 1 1)
					(thickness 0.15)
				)
				(justify mirror)
			)
		)
		(property "Val" "1k"
			(at 142.48 291.85 0)
			(layer "B.Fab")
			(hide yes)
			(effects
				(font
					(size 1 1)
					(thickness 0.15)
				)
				(justify mirror)
			)
		)
		(sheetname "/RoT/")
		(sheetfile "rot.kicad_sch")
		(attr smd)
		(fp_rect
			(start -0.925 0.47)
			(end 0.925 -0.47)
			(stroke
				(width 0.05)
				(type default)
			)
			(fill no)
			(layer "B.CrtYd")
		)
		(fp_rect
			(start -0.5 0.25)
			(end 0.5 -0.25)
			(stroke
				(width 0.15)
				(type solid)
			)
			(fill no)
			(layer "B.Fab")
		)
		(pad "1" smd roundrect
			(at -0.48 0 180)
			(size 0.59 0.64)
			(layers "B.Cu" "B.Mask" "B.Paste")
			(roundrect_rratio 0.25)
			(net 2 "VCC3V3")
			(pintype "passive")
		)
		(pad "2" smd roundrect
			(at 0.48 0 180)
			(size 0.59 0.64)
			(layers "B.Cu" "B.Mask" "B.Paste")
			(roundrect_rratio 0.25)
			(net 130 "QSPIA_CLK")
			(pintype "passive")
		)
	)
)
